# S9S_MB_2U (Grand Teton) — schematic netlist excerpt (pin names and nets, part order shuffled) for the footprints in the layout excerpt that follows; sources: Cadence DE-HDL packaged netlist, KiCad conversion of 03242023_DA0F0TMBIJ0_F0T_Motherboard_J_brd_V01_OCP.brd

C1931  Q_CAP  0.01UF 50V 10% X7R  pkg C0402  page 217 : A = VCC_PLD_CORE ; B = GND
PC1900  Q_CAPP  330UF 2.5V +10/-35% SPCAP  pkg SMLF  page 276 : A = PVCCFA_EHV_CPU0 ; B = GND

(kicad_pcb
	(version 20260206)
	(generator "pcbnew")
	(generator_version "10.0")
	(general
		(thickness 1.6)
		(legacy_teardrops no)
	)
	(paper "A4")
	(title_block
		(title "03242023_DA0F0TMBIJ0_F0T_Motherboard_J_brd_V01_OCP.brd")
		(comment 1 "Grand Teton / footprints 5319-5320 of 6105")
	)
	(layers
		(0 "F.Cu" signal "TOP")
		(4 "In1.Cu" signal "GND")
		(6 "In2.Cu" signal "IN1")
		(8 "In3.Cu" signal "GND1")
		(10 "In4.Cu" signal "IN2")
		(12 "In5.Cu" signal "GND2")
		(14 "In6.Cu" signal "IN3")
		(16 "In7.Cu" signal "GND3")
		(18 "In8.Cu" signal "VCC")
		(20 "In9.Cu" signal "VCC1")
		(22 "In10.Cu" signal "GND4")
		(24 "In11.Cu" signal "IN4")
		(26 "In12.Cu" signal "GND5")
		(28 "In13.Cu" signal "IN5")
		(30 "In14.Cu" signal "GND6")
		(32 "In15.Cu" signal "IN6")
		(34 "In16.Cu" signal "GND7")
		(2 "B.Cu" signal "BOTTOM")
		(9 "F.Adhes" user "F.Adhesive")
		(11 "B.Adhes" user "B.Adhesive")
		(13 "F.Paste" user "Package Geometry/Pastemask Top")
		(15 "B.Paste" user "Package Geometry/Pastemask Bottom")
		(5 "F.SilkS" user "Ref Des/Silkscreen Top")
		(7 "B.SilkS" user "Ref Des/Silkscreen Bottom")
		(1 "F.Mask" user "Board Geometry/Soldermask Top")
		(3 "B.Mask" user "Board Geometry/Soldermask Bottom")
		(17 "Dwgs.User" user "User.Drawings")
		(19 "Cmts.User" user "User.Comments")
		(21 "Eco1.User" user "User.Eco1")
		(23 "Eco2.User" user "User.Eco2")
		(25 "Edge.Cuts" user "Board Geometry/Outline")
		(27 "Margin" user)
		(31 "F.CrtYd" user "Package Geometry/Place Bound Top")
		(29 "B.CrtYd" user "Package Geometry/Place Bound Bottom")
		(35 "F.Fab" user "Ref Des/Assembly Top")
		(33 "B.Fab" user "Ref Des/Assembly Bottom")
	)
	(footprint ""
		(layer "B.Cu")
		(at 178.1556 -112.57534 90)
		(property "Reference" "C1931"
			(at 0 0 90)
			(layer "B.SilkS")
			(hide yes)
			(effects
				(font
					(size 1.27 1.27)
				)
				(justify mirror)
			)
		)
		(property "Value" ""
			(at 0 0 90)
			(layer "B.Fab")
			(effects
				(font
					(size 1.27 1.27)
				)
				(justify mirror)
			)
		)
		(duplicate_pad_numbers_are_jumpers no)
		(fp_line
			(start 0.69215 -0.2921)
			(end -0.69215 -0.2921)
			(stroke
				(width 0.1524)
				(type default)
			)
			(layer "B.SilkS")
		)
		(fp_line
			(start -0.69215 -0.2921)
			(end -0.69215 0.2921)
			(stroke
				(width 0.1524)
				(type default)
			)
			(layer "B.SilkS")
		)
		(fp_line
			(start 0.69215 0.2921)
			(end 0.69215 -0.2921)
			(stroke
				(width 0.1524)
				(type default)
			)
			(layer "B.SilkS")
		)
		(fp_line
			(start -0.69215 0.2921)
			(end 0.69215 0.2921)
			(stroke
				(width 0.1524)
				(type default)
			)
			(layer "B.SilkS")
		)
		(fp_line
			(start 0.51435 -0.2794)
			(end -0.51435 -0.2794)
			(stroke
				(width 0.1)
				(type default)
			)
			(layer "B.Fab")
		)
		(fp_line
			(start -0.51435 -0.2794)
			(end -0.51435 0.2794)
			(stroke
				(width 0.1)
				(type default)
			)
			(layer "B.Fab")
		)
		(fp_line
			(start 0.51435 0.2794)
			(end 0.51435 -0.2794)
			(stroke
				(width 0.1)
				(type default)
			)
			(layer "B.Fab")
		)
		(fp_line
			(start -0.51435 0.2794)
			(end 0.51435 0.2794)
			(stroke
				(width 0.1)
				(type default)
			)
			(layer "B.Fab")
		)
		(pad "1" smd circle
			(at 0.40005 0 270)
			(size 0 0)
			(layers "B.Cu" "B.Mask" "B.Paste")
			(net "VCC_PLD_CORE")
		)
		(pad "2" smd circle
			(at -0.40005 0 270)
			(size 0 0)
			(layers "B.Cu" "B.Mask" "B.Paste")
			(net "GND")
		)
		(zone
			(layer "B.Cu")
			(hatch none 0.5)
			(connect_pads
				(clearance 0)
			)
			(min_thickness 0.25)
			(keepout
				(tracks not_allowed)
				(vias allowed)
				(pads allowed)
				(copperpour not_allowed)
				(footprints allowed)
			)
			(placement
				(enabled no)
				(sheetname "")
			)
			(fill
				(thermal_gap 0.5)
				(thermal_bridge_width 0.5)
				(island_removal_mode 0)
			)
			(polygon
				(pts
					(xy 178.24323 -112.76584) (xy 178.301396 -112.6744) (xy 178.301396 -112.47501) (xy 178.24323 -112.38484)
					(xy 178.06797 -112.38484) (xy 178.00955 -112.47501) (xy 178.00955 -112.6744) (xy 178.067716 -112.76584)
				)
			)
		)
	)
	(footprint ""
		(layer "B.Cu")
		(at 410.902658 -153.147522 180)
		(property "Reference" "PC1900"
			(at 0 0 0)
			(layer "B.SilkS")
			(hide yes)
			(effects
				(font
					(size 1.27 1.27)
				)
				(justify mirror)
			)
		)
		(property "Value" ""
			(at 0 0 0)
			(layer "B.Fab")
			(effects
				(font
					(size 1.27 1.27)
				)
				(justify mirror)
			)
		)
		(duplicate_pad_numbers_are_jumpers no)
		(fp_line
			(start 4.533392 2.249932)
			(end 4.533392 -2.249932)
			(stroke
				(width 0.1524)
				(type default)
			)
			(layer "B.SilkS")
		)
		(fp_line
			(start 4.533392 -2.249932)
			(end -4.533392 -2.249932)
			(stroke
				(width 0.1524)
				(type default)
			)
			(layer "B.SilkS")
		)
		(fp_line
			(start -4.533392 2.249932)
			(end 4.533392 2.249932)
			(stroke
				(width 0.1524)
				(type default)
			)
			(layer "B.SilkS")
		)
		(fp_line
			(start -4.533392 -2.249932)
			(end -4.533392 2.249932)
			(stroke
				(width 0.1524)
				(type default)
			)
			(layer "B.SilkS")
		)
		(fp_rect
			(start 5.39242 -2.326132)
			(end 4.533392 2.326132)
			(stroke
				(width 0)
				(type default)
			)
			(fill yes)
			(layer "B.SilkS")
		)
		(fp_line
			(start 3.750056 2.249932)
			(end 3.750056 -2.249932)
			(stroke
				(width 0.1)
				(type default)
			)
			(layer "B.Fab")
		)
		(fp_line
			(start 3.750056 -2.249932)
			(end -3.750056 -2.249932)
			(stroke
				(width 0.1)
				(type default)
			)
			(layer "B.Fab")
		)
		(fp_line
			(start -3.750056 2.249932)
			(end 3.750056 2.249932)
			(stroke
				(width 0.1)
				(type default)
			)
			(layer "B.Fab")
		)
		(fp_line
			(start -3.750056 -2.249932)
			(end -3.750056 2.249932)
			(stroke
				(width 0.1)
				(type default)
			)
			(layer "B.Fab")
		)
		(fp_text user "+"
			(at 6.322314 0.786384 90)
			(unlocked yes)
			(layer "B.SilkS")
			(effects
				(font
					(size 1.905 1.4224)
					(thickness 0.1524)
				)
				(justify left mirror)
			)
		)
		(fp_text user "-"
			(at -4.8514 -0.14605 180)
			(unlocked yes)
			(layer "B.SilkS")
			(effects
				(font
					(size 1.905 1.4224)
					(thickness 0.1524)
				)
				(justify left mirror)
			)
		)
		(fp_text user "+"
			(at 6.322314 0.786384 90)
			(unlocked yes)
			(layer "B.Fab")
			(effects
				(font
					(size 1.905 1.4224)
					(thickness 0.1524)
				)
				(justify left mirror)
			)
		)
		(fp_text user "-"
			(at -4.8514 -0.14605 180)
			(unlocked yes)
			(layer "B.Fab")
			(effects
				(font
					(size 1.905 1.4224)
					(thickness 0.1524)
				)
				(justify left mirror)
			)
		)
		(pad "1" smd rect
			(at 3.199892 0)
			(size 2.413 2.8194)
			(layers "B.Cu" "B.Mask" "B.Paste")
			(net "PVCCFA_EHV_CPU0")
		)
		(pad "2" smd rect
			(at -3.199892 0)
			(size 2.413 2.8194)
			(layers "B.Cu" "B.Mask" "B.Paste")
			(net "GND")
		)
	)
)
